# BASEBOARD_FAB2 (Tioga Pass) — schematic netlist excerpt (pin names and nets, part order shuffled) for the footprints in the layout excerpt that follows; sources: Cadence DE-HDL packaged netlist, KiCad conversion of Wiwynn_Tioga_Pass_MB.brd

R7P11  RES  49.9 1% CHIP  pkg 0402  page 55 : A = A_CPU1_UPI2_RBIAS ; B = GND

T1D11  TEST-PAD-12P-1-GP-U  pkg DISCRET-GB1  page 257
  DP  = L14_85OHM_5INCH_DP
  DN  = L14_85OHM_5INCH_DN
  GND(0)  = GND
  GND(1)  = GND
  GND(2)  = GND
  GND(3)  = GND
  GND(4)  = GND
  GND(5)  = GND
  GND(6)  = GND
  GND(7)  = GND
  GND(8)  = GND
  GND(9)  = GND

(kicad_pcb
	(version 20260206)
	(generator "pcbnew")
	(generator_version "10.0")
	(general
		(thickness 1.6)
		(legacy_teardrops no)
	)
	(paper "A4")
	(title_block
		(title "Wiwynn_Tioga_Pass_MB.brd")
		(comment 1 "Tioga Pass / footprints 2994-2995 of 4770")
	)
	(layers
		(0 "F.Cu" signal "TOP")
		(4 "In1.Cu" signal "L2GND")
		(6 "In2.Cu" signal "L3")
		(8 "In3.Cu" signal "L4GND")
		(10 "In4.Cu" signal "L5")
		(12 "In5.Cu" signal "L6GND")
		(14 "In6.Cu" signal "L7VCC")
		(16 "In7.Cu" signal "L8VCC")
		(18 "In8.Cu" signal "L9GND")
		(20 "In9.Cu" signal "L10")
		(22 "In10.Cu" signal "L11GND")
		(24 "In11.Cu" signal "L12")
		(26 "In12.Cu" signal "L13GND")
		(2 "B.Cu" signal "BOTTOM")
		(9 "F.Adhes" user "F.Adhesive")
		(11 "B.Adhes" user "B.Adhesive")
		(13 "F.Paste" user "Package Geometry/Pastemask Top")
		(15 "B.Paste" user "Package Geometry/Pastemask Bottom")
		(5 "F.SilkS" user "Ref Des/Silkscreen Top")
		(7 "B.SilkS" user "Ref Des/Silkscreen Bottom")
		(1 "F.Mask" user "Board Geometry/Soldermask Top")
		(3 "B.Mask" user "Board Geometry/Soldermask Bottom")
		(17 "Dwgs.User" user "User.Drawings")
		(19 "Cmts.User" user "User.Comments")
		(21 "Eco1.User" user "User.Eco1")
		(23 "Eco2.User" user "User.Eco2")
		(25 "Edge.Cuts" user "Board Geometry/Outline")
		(27 "Margin" user)
		(31 "F.CrtYd" user "Package Geometry/Place Bound Top")
		(29 "B.CrtYd" user "Package Geometry/Place Bound Bottom")
		(35 "F.Fab" user "Ref Des/Assembly Top")
		(33 "B.Fab" user "Ref Des/Assembly Bottom")
	)
	(footprint ""
		(layer "B.Cu")
		(at 53.80228 -165.01618 90)
		(property "Reference" "T1D11"
			(at 0 0 90)
			(layer "B.SilkS")
			(hide yes)
			(effects
				(font
					(size 1.27 1.27)
				)
				(justify mirror)
			)
		)
		(property "Value" "*"
			(at 3.4036 -4.46405 90)
			(unlocked yes)
			(layer "B.Fab")
			(hide yes)
			(effects
				(font
					(size 0.889 0.889)
					(thickness 0.1524)
				)
				(justify mirror)
			)
		)
		(property "Device Type" "TEST-PAD-12P-1-GP-U_DISCRET-GBA"
			(at 3.4036 -5.98805 90)
			(unlocked yes)
			(layer "B.Fab")
			(hide yes)
			(effects
				(font
					(size 0.889 0.889)
					(thickness 0.1524)
				)
				(justify mirror)
			)
		)
		(duplicate_pad_numbers_are_jumpers no)
		(fp_line
			(start 2.3876 -4.826)
			(end -2.3622 -4.826)
			(stroke
				(width 0.1524)
				(type default)
			)
			(layer "B.SilkS")
		)
		(fp_line
			(start -2.3622 -4.826)
			(end -2.3622 3.4798)
			(stroke
				(width 0.1524)
				(type default)
			)
			(layer "B.SilkS")
		)
		(fp_line
			(start 2.3876 3.4798)
			(end 2.3876 -4.826)
			(stroke
				(width 0.1524)
				(type default)
			)
			(layer "B.SilkS")
		)
		(fp_line
			(start -2.3622 3.4798)
			(end 2.3876 3.4798)
			(stroke
				(width 0.1524)
				(type default)
			)
			(layer "B.SilkS")
		)
		(fp_rect
			(start 2.6416 3.7338)
			(end -2.6162 -5.08)
			(stroke
				(width 0)
				(type default)
			)
			(fill no)
			(layer "B.CrtYd")
		)
		(fp_rect
			(start 2.6416 3.7338)
			(end -2.6162 -5.08)
			(stroke
				(width 0)
				(type default)
			)
			(fill no)
			(layer "B.Fab")
		)
		(pad "1" smd circle
			(at -0.496824 -1.301496 270)
			(size 0.6604 0.6604)
			(layers "B.Cu" "B.Mask" "B.Paste")
			(net "L14_85OHM_5INCH_DP")
		)
		(pad "2" smd circle
			(at 0.503936 -1.301496 270)
			(size 0.6604 0.6604)
			(layers "B.Cu" "B.Mask" "B.Paste")
			(net "L14_85OHM_5INCH_DN")
		)
		(pad "3" smd custom
			(at 0.00889 0.370078 270)
			(size 0.74295 0.74295)
			(layers "B.Cu" "B.Mask" "B.Paste")
			(net "GND")
			(options
				(clearance outline)
				(anchor circle)
			)
			(primitives
				(gr_poly
					(pts
						(xy -2.1209 -1.4859) (xy 2.1209 -1.4859) (xy 2.1209 1.4859) (xy 1.08585 1.4859) (xy 1.08585 0.4699)
						(xy -1.08585 0.4699) (xy -1.08585 1.4859) (xy -2.1209 1.4859)
					)
					(width 0)
					(fill yes)
				)
			)
		)
		(pad "4" thru_hole circle
			(at -1.266444 -3.851656 270)
			(size 1.4478 1.4478)
			(drill 1.0414)
			(layers "*.Cu" "*.Mask")
			(remove_unused_layers no)
			(net "GND")
			(clearance 0.1524)
			(thermal_gap 0.1524)
		)
		(pad "5" thru_hole circle
			(at 1.273556 -3.851656 270)
			(size 1.4478 1.4478)
			(drill 1.0414)
			(layers "*.Cu" "*.Mask")
			(remove_unused_layers no)
			(net "GND")
			(clearance 0.1524)
			(thermal_gap 0.1524)
		)
		(pad "6" thru_hole circle
			(at -1.266444 2.498344 270)
			(size 1.4478 1.4478)
			(drill 1.0414)
			(layers "*.Cu" "*.Mask")
			(remove_unused_layers no)
			(net "GND")
			(clearance 0.1524)
			(thermal_gap 0.1524)
		)
		(pad "7" thru_hole circle
			(at 1.273556 2.498344 270)
			(size 1.4478 1.4478)
			(drill 1.0414)
			(layers "*.Cu" "*.Mask")
			(remove_unused_layers no)
			(net "GND")
			(clearance 0.1524)
			(thermal_gap 0.1524)
		)
		(pad "8" thru_hole circle
			(at -1.27 -0.4572 270)
			(size 0.7112 0.7112)
			(drill 0.4064)
			(layers "*.Cu" "*.Mask")
			(remove_unused_layers no)
			(net "GND")
			(clearance 0.1016)
			(thermal_gap 0.1016)
		)
		(pad "9" thru_hole circle
			(at -1.27 0.762 270)
			(size 0.7112 0.7112)
			(drill 0.4064)
			(layers "*.Cu" "*.Mask")
			(remove_unused_layers no)
			(net "GND")
			(clearance 0.1016)
			(thermal_gap 0.1016)
		)
		(pad "10" thru_hole circle
			(at 0.0254 0.762 270)
			(size 0.7112 0.7112)
			(drill 0.4064)
			(layers "*.Cu" "*.Mask")
			(remove_unused_layers no)
			(net "GND")
			(clearance 0.1016)
			(thermal_gap 0.1016)
		)
		(pad "11" thru_hole circle
			(at 1.27 0.762 270)
			(size 0.7112 0.7112)
			(drill 0.4064)
			(layers "*.Cu" "*.Mask")
			(remove_unused_layers no)
			(net "GND")
			(clearance 0.1016)
			(thermal_gap 0.1016)
		)
		(pad "12" thru_hole circle
			(at 1.27 -0.4572 270)
			(size 0.7112 0.7112)
			(drill 0.4064)
			(layers "*.Cu" "*.Mask")
			(remove_unused_layers no)
			(net "GND")
			(clearance 0.1016)
			(thermal_gap 0.1016)
		)
	)
	(footprint ""
		(layer "B.Cu")
		(at 117.221 -77.216 -90)
		(property "Reference" "R7P11"
			(at 0 0 90)
			(layer "B.SilkS")
			(hide yes)
			(effects
				(font
					(size 1.27 1.27)
				)
				(justify mirror)
			)
		)
		(property "Value" ""
			(at 0 0 90)
			(layer "B.Fab")
			(effects
				(font
					(size 1.27 1.27)
				)
				(justify mirror)
			)
		)
		(duplicate_pad_numbers_are_jumpers no)
		(fp_poly
			(pts
				(xy 0.2794 -0.1016) (xy -0.2794 -0.1016) (xy -0.2794 0.9906) (xy 0.2794 0.9906)
			)
			(stroke
				(width 0)
				(type default)
			)
			(fill no)
			(layer "B.CrtYd")
		)
		(fp_line
			(start -0.2794 0.9906)
			(end -0.2794 -0.1016)
			(stroke
				(width 0.1)
				(type default)
			)
			(layer "B.Fab")
		)
		(fp_line
			(start 0.2794 0.9906)
			(end -0.2794 0.9906)
			(stroke
				(width 0.1)
				(type default)
			)
			(layer "B.Fab")
		)
		(fp_line
			(start -0.2794 -0.1016)
			(end 0.2794 -0.1016)
			(stroke
				(width 0.1)
				(type default)
			)
			(layer "B.Fab")
		)
		(fp_line
			(start 0.2794 -0.1016)
			(end 0.2794 0.9906)
			(stroke
				(width 0.1)
				(type default)
			)
			(layer "B.Fab")
		)
		(pad "1" smd rect
			(at 0 0 90)
			(size 0.508 0.508)
			(layers "B.Cu" "B.Mask" "B.Paste")
			(net "A_CPU1_UPI2_RBIAS")
		)
		(pad "2" smd rect
			(at 0 0.889 90)
			(size 0.508 0.508)
			(layers "B.Cu" "B.Mask" "B.Paste")
			(net "GND")
		)
		(zone
			(layer "B.Cu")
			(hatch none 0.5)
			(connect_pads
				(clearance 0)
			)
			(min_thickness 0.25)
			(keepout
				(tracks not_allowed)
				(vias allowed)
				(pads allowed)
				(copperpour not_allowed)
				(footprints allowed)
			)
			(placement
				(enabled no)
				(sheetname "")
			)
			(fill
				(thermal_gap 0.5)
				(thermal_bridge_width 0.5)
				(island_removal_mode 0)
			)
			(polygon
				(pts
					(xy 116.586 -76.962) (xy 116.586 -77.47) (xy 116.967 -77.47) (xy 116.967 -76.962)
				)
			)
		)
		(zone
			(layer "B.Cu")
			(hatch none 0.5)
			(connect_pads
				(clearance 0)
			)
			(min_thickness 0.25)
			(keepout
				(tracks allowed)
				(vias not_allowed)
				(pads allowed)
				(copperpour not_allowed)
				(footprints allowed)
			)
			(placement
				(enabled no)
				(sheetname "")
			)
			(fill
				(thermal_gap 0.5)
				(thermal_bridge_width 0.5)
				(island_removal_mode 0)
			)
			(polygon
				(pts
					(xy 116.967 -76.962) (xy 116.967 -77.47) (xy 116.586 -77.47) (xy 116.586 -76.962)
				)
			)
		)
	)
)
